FILE_TYPE = CONNECTIVITY;
{Allegro Design Entry HDL 16.6-p007 (v16-6-112F) 10/10/2012}
"PAGE_NUMBER" = 230;
0"NC";
1"GND\g";
2"GND\g";
3"GND\g";
4"GND\g";
5"GND\g";
6"GND\g";
7"GND\g";
8"GND\g";
9"PVDDQ_KLM\g";
10"GND\g";
11"P3V3\g";
12"P3V3\g";
13"GND\g";
14"PVTT_KLM\g";
15"PVTT_KLM\g";
16"PWRGD_PVTT_CPU1";
17"VR_PVTT_KLM_SNS";
18"PWRGD_PVTT_KLM_CPU1_R";
19"VR_PVTT_KLM_VREF";
20"VR_PVTT_KLM_BIAS";
21"VSENSE_PVDDQ_KLM_VTT";
22"FM_PVTT_KLM_EN_R";
23"PWRGD_PVDDQ_KLM";
%"GND"
"1","(3750,3050)","0","mstr_symbols","I10";
;
HDL_POWER"GND"
BOM_COST"MEM_KLM_VTT_DEF"
ROOM"VTT_KLM_PWR_VR"
CDS_LIB"mstr_symbols"
VOLTAGE"0.0V"
BODY_TYPE"PLUMBING"
SIZE"1B";
"A\NAC"1;
%"GND"
"1","(3875,1400)","0","mstr_symbols","I15";
;
HDL_POWER"GND"
SIZE"1B"
CDS_LIB"mstr_symbols"
VOLTAGE"0.0V"
BODY_TYPE"PLUMBING";
"A\NAC"2;
%"CAP"
"1","(3875,1650)","2","mstr_discrete","I16";
;
CDS_SEC"1"
CDS_LIB"mstr_discrete"
ROOM"VTT_KLM_PWR_VR"
BOM_COST"MEM_VRD_VTT_KLM"
SEC_TYPE"0402LF"
CDS_LOCATION"C4A3"
SEC"1"
MATERIAL"X7R"
VOLTAGE"50V"
TOLERANCE"10%"
VALUE"1000PF"
LOCATION"C4A3"
PACK_TYPE"0402LF"
PART_NUMBER"A36096-046";
"A"
$PN"1"18;
"B"
$PN"2"2;
%"RES"
"2","(3500,2025)","2","mstr_discrete","I17";
;
CDS_SEC"1"
SEC_TYPE"0402"
BOM_COST"MEM_VRD_VTT_KLM"
SEC"1"
CDS_LOCATION"R4A5"
ROOM"VTT_KLM_PWR_VR"
CDS_LIB"mstr_discrete"
TOLERANCE"1%"
LOCATION"R4A5"
VALUE"10.0K"
PACK_TYPE"0402"
MATERIAL"CHIP"
PART_NUMBER"G21796-016"
WATTAGE"1/16W";
"A"
$PN"1"12;
"B"
$PN"2"18;
%"CAP"
"1","(4000,1050)","0","mstr_discrete","I18";
;
CDS_SEC"1"
SEC"1"
BOM_COST"MEM_VRD_VTT_KLM"
SEC_TYPE"0805LF"
ROOM"VTT_KLM_PWR_VR"
CDS_LOCATION"C4A13"
CDS_LIB"mstr_discrete"
LOCATION"C4A13"
VALUE"22UF"
TOLERANCE"20%"
PACK_TYPE"0805LF"
VOLTAGE"4V"
MATERIAL"X6S"
PART_NUMBER"C95333-002";
"A"
$PN"1"15;
"B"
$PN"2"3;
%"GND"
"1","(4000,675)","0","mstr_symbols","I19";
;
HDL_POWER"GND"
VOLTAGE"0.0V"
BODY_TYPE"PLUMBING"
CDS_LIB"mstr_symbols"
SIZE"1B";
"A\NAC"3;
%"CAP"
"1","(2350,875)","0","mstr_discrete","I21";
;
CDS_SEC"1"
ROOM"VTT_KLM_PWR_VR"
SEC"1"
BOM_COST"MEM_VRD_VTT_KLM"
SEC_TYPE"0402"
CDS_LOCATION"C4A14"
CDS_LIB"mstr_discrete"
PART_NUMBER"D97712-011"
VOLTAGE"16V"
MATERIAL"X6S"
LOCATION"C4A14"
VALUE"1.0UF"
TOLERANCE"10%"
PACK_TYPE"0402";
"A"
$PN"1"19;
"B"
$PN"2"4;
%"GND"
"1","(2350,600)","0","mstr_symbols","I22";
;
HDL_POWER"GND"
VOLTAGE"0.0V"
BODY_TYPE"PLUMBING"
SIZE"1B"
CDS_LIB"mstr_symbols";
"A\NAC"4;
%"GND"
"1","(2025,600)","0","mstr_symbols","I23";
;
SIZE"1B"
HDL_POWER"GND"
VOLTAGE"0.0V"
BODY_TYPE"PLUMBING"
CDS_LIB"mstr_symbols";
"A\NAC"5;
%"GND"
"1","(475,2125)","0","mstr_symbols","I24";
;
SIZE"1B"
HDL_POWER"GND"
VOLTAGE"0.0V"
BODY_TYPE"PLUMBING"
CDS_LIB"mstr_symbols"
ROOM"VTT_KLM_PWR_VR"
BOM_COST"MEM_VRD_VTT_KLM";
"A\NAC"6;
%"CAP"
"1","(475,2400)","0","mstr_discrete","I25";
;
CDS_SEC"1"
BOM_COST"MEM_VRD_VTT_KLM"
SEC_TYPE"0603LF"
SEC"1"
ROOM"VTT_KLM_PWR_VR"
CDS_LOCATION"C4A15"
CDS_LIB"mstr_discrete"
MATERIAL"X6S"
VOLTAGE"4V"
PACK_TYPE"0603LF"
TOLERANCE"20%"
VALUE"10UF"
PART_NUMBER"E15431-001"
LOCATION"C4A15";
"A"
$PN"1"9;
"B"
$PN"2"6;
%"CAP"
"1","(50,2375)","0","mstr_discrete","I26";
;
CDS_SEC"1"
SEC"1"
SEC_TYPE"0603LF"
BOM_COST"MEM_VRD_VTT_KLM"
ROOM"VTT_KLM_PWR_VR"
CDS_LIB"mstr_discrete"
CDS_LOCATION"C6L5"
PART_NUMBER"E15431-001"
PACK_TYPE"0603LF"
VOLTAGE"4V"
TOLERANCE"20%"
VALUE"10UF"
LOCATION"C6L5"
MATERIAL"X6S";
"A"
$PN"1"9;
"B"
$PN"2"7;
%"GND"
"1","(50,2125)","0","mstr_symbols","I27";
;
HDL_POWER"GND"
VOLTAGE"0.0V"
BODY_TYPE"PLUMBING"
CDS_LIB"mstr_symbols"
SIZE"1B"
ROOM"VTT_KLM_PWR_VR"
BOM_COST"MEM_VRD_VTT_KLM";
"A\NAC"7;
%"CAP"
"1","(475,1525)","0","mstr_discrete","I28";
;
CDS_SEC"1"
SEC_TYPE"0402"
BOM_COST"MEM_VRD_VTT_KLM"
SEC"1"
CDS_LOCATION"C4A8"
ROOM"VTT_KLM_PWR_VR"
CDS_LIB"mstr_discrete"
VOLTAGE"16V"
VALUE"1.0UF"
LOCATION"C4A8"
MATERIAL"X6S"
TOLERANCE"10%"
PACK_TYPE"0402"
PART_NUMBER"D97712-011";
"A"
$PN"1"20;
"B"
$PN"2"8;
%"GND"
"1","(475,1275)","0","mstr_symbols","I29";
;
SIZE"1B"
HDL_POWER"GND"
CDS_LIB"mstr_symbols"
BODY_TYPE"PLUMBING"
VOLTAGE"0.0V";
"A\NAC"8;
%"RES"
"1","(150,1775)","0","mstr_discrete","I30";
;
CDS_SEC"1"
ROOM"VTT_KLM_PWR_VR"
SEC"1"
CDS_LOCATION"R6L8"
BOM_COST"MEM_VRD_VTT_KLM"
SEC_TYPE"0402"
CDS_LIB"mstr_discrete"
PART_NUMBER"G21497-005"
MATERIAL"CHIP"
LOCATION"R6L8"
TOLERANCE"5%"
PACK_TYPE"0402"
VALUE"0.0"
WATTAGE"1/16W";
"B"
$PN"2"20;
"A"
$PN"1"11;
%"MIC5166"
"1","(1575,1075)","0","mstr_vreg","I31";
;
CDS_SEC"1"
CDS_LIB"mstr_vreg"
CDS_LMAN_SYM_OUTLINE"-250,350,250,-350"
PACK_TYPE"DFN"
SEC"1"
SEC_TYPE"DFN"
BOM_COST"MEM_VRD_VTT_KLM"
ROOM"VTT_KLM_PWR_VR"
CDS_LOCATION"EU4A2"
LOCATION"EU4A2"
MATERIAL"IC"
PART_NUMBER"H55101-001";
"THPAD"
$PN"11"5;
"VTT"
$PN"9"15;
"PGND"
$PN"8"5;
"SNS"
$PN"6"17;
"VDDQ"
$PN"4"21;
"PG"
$PN"5"18;
"AGND"
$PN"3"5;
"BIAS"
$PN"2"20;
"VREF"
$PN"1"19;
"VIN"
$PN"10"9;
"EN"
$PN"7"22;
%"RES"
"2","(-675,1575)","1","mstr_discrete","I34";
;
CDS_SEC"1"
ROOM"VTT_KLM_PWR_VR"
SEC"1"
NO_XNET_CONNECTION"1"
CDS_LOCATION"R6L6"
BOM_COST"MEM_VRD_VTT_KLM"
SEC_TYPE"0402"
CDS_LIB"mstr_discrete"
PACK_TYPE"0402"
PART_NUMBER"G21497-005"
WATTAGE"1/16W"
LOCATION"R6L6"
VALUE"0.0"
TOLERANCE"5%"
MATERIAL"CHIP";
"A"
$PN"1"9;
"B"
$PN"2"21;
%"PVDDQ_KLM"
"1","(-1425,2800)","0","mstr_symbols","I35";
;
VOLTAGE"1.2V"
HDL_POWER"PVDDQ_KLM"
BODY_TYPE"PLUMBING"
CDS_LIB"mstr_symbols";
"G\NAC"9;
%"RES"
"2","(-300,675)","2","mstr_discrete","I37";
;
CDS_SEC"1"
ROOM"VTT_KLM_PWR_VR"
CDS_LOCATION"R6L5"
SEC"1"
SEC_TYPE"0402"
BOM_COST"MEM_VRD_VTT_KLM"
CDS_LIB"mstr_discrete"
LOCATION"R6L5"
VALUE"1.0M"
MATERIAL"EMPTY"
TOLERANCE"1%"
WATTAGE"1/16W"
PACK_TYPE"0402"
PART_NUMBER"G21796-021";
"A"
$PN"1"11;
"B"
$PN"2"22;
%"RES"
"1","(-500,150)","0","mstr_discrete","I38";
;
CDS_SEC"1"
CDS_LIB"mstr_discrete"
ROOM"VTT_KLM_PWR_VR"
CDS_LOCATION"R4A3"
SEC"1"
BOM_COST"MEM_VRD_VTT_KLM"
SEC_TYPE"0402"
TOLERANCE"5%"
LOCATION"R4A3"
PART_NUMBER"G21497-005"
VALUE"0.0"
WATTAGE"1/16W"
PACK_TYPE"0402"
MATERIAL"CHIP";
"B"
$PN"2"22;
"A"
$PN"1"23;
%"CAP"
"1","(-350,-375)","2","mstr_discrete","I39";
;
CDS_SEC"1"
ROOM"VTT_KLM_PWR_VR"
SEC"1"
SEC_TYPE"0402LF"
BOM_COST"MEM_VRD_VTT_KLM"
CDS_LOCATION"C4A6"
CDS_LIB"mstr_discrete"
PART_NUMBER"A36096-046"
VOLTAGE"50V"
TOLERANCE"10%"
MATERIAL"EMPTY"
LOCATION"C4A6"
VALUE"1000PF"
PACK_TYPE"0402LF";
"A"
$PN"1"22;
"B"
$PN"2"10;
%"GND"
"1","(-350,-600)","0","mstr_symbols","I40";
;
HDL_POWER"GND"
VOLTAGE"0.0V"
BODY_TYPE"PLUMBING"
SIZE"1B"
CDS_LIB"mstr_symbols";
"A\NAC"10;
%"P3V3"
"1","(-375,2075)","0","mstr_symbols","I42";
;
SIZE"1B"
CDS_LIB"mstr_symbols"
BODY_TYPE"PLUMBING"
VOLTAGE"3.3V"
HDL_POWER"P3V3";
"G\NAC"11;
%"P3V3"
"1","(3500,2325)","0","mstr_symbols","I43";
;
SIZE"1B"
CDS_LIB"mstr_symbols"
VOLTAGE"3.3V"
BODY_TYPE"PLUMBING"
HDL_POWER"P3V3";
"G\NAC"12;
%"GND"
"1","(375,775)","0","mstr_symbols","I45";
;
CDS_LIB"mstr_symbols"
HDL_POWER"GND"
VOLTAGE"0.0V"
BODY_TYPE"PLUMBING"
SIZE"1B";
"A\NAC"13;
%"CAP"
"1","(375,975)","0","mstr_discrete","I46";
;
CDS_SEC"1"
SEC_TYPE"0603"
SEC"1"
CDS_LOCATION"C4A7"
ROOM"VTT_KLM_PWR_VR"
CDS_LIB"mstr_discrete"
LOCATION"C4A7"
VALUE"4.7UF"
PART_NUMBER"E15431-003"
TOLERANCE"10%"
PACK_TYPE"0603"
VOLTAGE"6.3V"
MATERIAL"X6S";
"A"
$PN"1"21;
"B"
$PN"2"13;
%"CAP_A"
"1","(3025,3425)","0","dev_discrete","I47";
;
SEC"1"
SEC_TYPE"0603V"
CDS_SEC"1"
CDS_LOCATION"C8M12"
CDS_LIB"dev_discrete"
PART_NUMBER"602433-106"
LOCATION"C8M12"
VALUE"47UF"
TOLERANCE"20%"
PACK_TYPE"0603V"
VOLTAGE"4V"
MATERIAL"X5R";
"B"
$PN"2"1;
"A"
$PN"1"14;
%"CAP_A"
"1","(3375,3425)","0","dev_discrete","I48";
;
SEC"1"
SEC_TYPE"0603V"
CDS_SEC"1"
CDS_LIB"dev_discrete"
CDS_LOCATION"C8L3"
PART_NUMBER"602433-106"
LOCATION"C8L3"
VALUE"47UF"
TOLERANCE"20%"
VOLTAGE"4V"
MATERIAL"X5R"
PACK_TYPE"0603V";
"B"
$PN"2"1;
"A"
$PN"1"14;
%"CAP_A"
"1","(3775,3425)","0","dev_discrete","I49";
;
SEC"1"
SEC_TYPE"0603V"
CDS_SEC"1"
CDS_LOCATION"C8L4"
CDS_LIB"dev_discrete"
PART_NUMBER"602433-106"
LOCATION"C8L4"
VALUE"47UF"
VOLTAGE"4V"
MATERIAL"X5R"
PACK_TYPE"0603V"
TOLERANCE"20%";
"B"
$PN"2"1;
"A"
$PN"1"14;
%"RES"
"1","(4150,1850)","0","mstr_discrete","I51";
;
CDS_SEC"1"
SEC_TYPE"0402"
SEC"1"
CDS_LIB"mstr_discrete"
CDS_LOCATION"R4A4"
PACK_TYPE"0402"
PART_NUMBER"G21796-074"
LOCATION"R4A4"
MATERIAL"CHIP"
TOLERANCE"1%"
VALUE"33.2"
WATTAGE"1/16W";
"B"
$PN"2"16;
"A"
$PN"1"18;
%"RES"
"1","(4800,975)","1","mstr_discrete","I52";
;
$SEC"1"
CDS_SEC"1"
CDS_LIB"mstr_discrete"
CDS_LOCATION"R6L7"
PACK_TYPE"0402"
LOCATION"R6L7"
PART_NUMBER"G21796-208"
TOLERANCE"1.0%"
MATERIAL"CHIP"
WATTAGE"1/16W"
VALUE"51.1";
"B"
$PN"2"15;
"A"
$PN"1"3;
%"SHUNT"
"1","(4975,50)","0","mstr_misc","I53";
;
CDS_SEC"1"
CDS_LOCATION"SH8L1"
SEC_TYPE"SH0201"
SEC"1"
CDS_LIB"mstr_misc"
MATERIAL"EMPTY"
PACK_TYPE"SH0201"
PIN_SHORT"A:B"
LOCATION"SH8L1"
PART_NUMBER"N_A";
"A"
$PN"1"17;
"B"
$PN"2"15;
%"PVTT_KLM"
"1","(3025,3700)","0","mstr_symbols","I6";
;
BOM_COST"MEM_KLM_VTT_DEF"
ROOM"VTT_KLM_PWR_VR"
HDL_POWER"PVTT_KLM"
CDS_LIB"mstr_symbols"
VOLTAGE"0.6V"
BODY_TYPE"PLUMBING";
"G\NAC"14;
%"PVTT_KLM"
"1","(5550,1600)","0","mstr_symbols","I9";
;
CDS_LIB"mstr_symbols"
BODY_TYPE"PLUMBING"
HDL_POWER"PVTT_KLM"
VOLTAGE"0.6V";
"G\NAC"15;
END.
